(kicad_pcb
	(version 20260206)
	(generator "pcbnew")
	(generator_version "10.0")
	(general
		(thickness 1.6)
		(legacy_teardrops no)
	)
	(paper "A4")
	(title_block
		(title "Wiwynn_Tioga_Pass_MB.brd")
		(comment 1 "Tioga Pass / footprints 3652-3658 of 4770")
	)
	(layers
		(0 "F.Cu" signal "TOP")
		(4 "In1.Cu" signal "L2GND")
		(6 "In2.Cu" signal "L3")
		(8 "In3.Cu" signal "L4GND")
		(10 "In4.Cu" signal "L5")
		(12 "In5.Cu" signal "L6GND")
		(14 "In6.Cu" signal "L7VCC")
		(16 "In7.Cu" signal "L8VCC")
		(18 "In8.Cu" signal "L9GND")
		(20 "In9.Cu" signal "L10")
		(22 "In10.Cu" signal "L11GND")
		(24 "In11.Cu" signal "L12")
		(26 "In12.Cu" signal "L13GND")
		(2 "B.Cu" signal "BOTTOM")
		(9 "F.Adhes" user "F.Adhesive")
		(11 "B.Adhes" user "B.Adhesive")
		(13 "F.Paste" user "Package Geometry/Pastemask Top")
		(15 "B.Paste" user "Package Geometry/Pastemask Bottom")
		(5 "F.SilkS" user "Ref Des/Silkscreen Top")
		(7 "B.SilkS" user "Ref Des/Silkscreen Bottom")
		(1 "F.Mask" user "Board Geometry/Soldermask Top")
		(3 "B.Mask" user "Board Geometry/Soldermask Bottom")
		(17 "Dwgs.User" user "User.Drawings")
		(19 "Cmts.User" user "User.Comments")
		(21 "Eco1.User" user "User.Eco1")
		(23 "Eco2.User" user "User.Eco2")
		(25 "Edge.Cuts" user "Board Geometry/Outline")
		(27 "Margin" user)
		(31 "F.CrtYd" user "Package Geometry/Place Bound Top")
		(29 "B.CrtYd" user "Package Geometry/Place Bound Bottom")
		(35 "F.Fab" user "Ref Des/Assembly Top")
		(33 "B.Fab" user "Ref Des/Assembly Bottom")
	)
	(footprint ""
		(layer "B.Cu")
		(at 393.65047 -106.58221)
		(property "Reference" "C2N13"
			(at 0 0 0)
			(layer "B.SilkS")
			(hide yes)
			(effects
				(font
					(size 1.27 1.27)
				)
				(justify mirror)
			)
		)
		(property "Value" ""
			(at 0 0 0)
			(layer "B.Fab")
			(effects
				(font
					(size 1.27 1.27)
				)
				(justify mirror)
			)
		)
		(duplicate_pad_numbers_are_jumpers no)
		(fp_rect
			(start 0.2794 0.9144)
			(end -0.2794 -0.1143)
			(stroke
				(width 0)
				(type default)
			)
			(fill no)
			(layer "B.CrtYd")
		)
		(fp_line
			(start -0.2794 -0.1143)
			(end -0.2794 0.9144)
			(stroke
				(width 0.1)
				(type default)
			)
			(layer "B.Fab")
		)
		(fp_line
			(start -0.2794 0.9144)
			(end 0.2794 0.9144)
			(stroke
				(width 0.1)
				(type default)
			)
			(layer "B.Fab")
		)
		(fp_line
			(start 0.2794 -0.1143)
			(end -0.2794 -0.1143)
			(stroke
				(width 0.1)
				(type default)
			)
			(layer "B.Fab")
		)
		(fp_line
			(start 0.2794 0.9144)
			(end 0.2794 -0.1143)
			(stroke
				(width 0.1)
				(type default)
			)
			(layer "B.Fab")
		)
		(pad "1" smd custom
			(at 0 0 270)
			(size 0.10414 0.10414)
			(layers "B.Cu" "B.Mask" "B.Paste")
			(net "P1V05_PCH_STBY")
			(options
				(clearance outline)
				(anchor circle)
			)
			(primitives
				(gr_poly
					(pts
						(xy -0.20828 -0.08636) (xy -0.20828 0.08636) (xy -0.08636 0.20828) (xy 0.086614 0.20828) (xy 0.20828 0.086614)
						(xy 0.20828 -0.08636) (xy 0.08636 -0.20828) (xy -0.08636 -0.20828)
					)
					(width 0)
					(fill yes)
				)
			)
		)
		(pad "2" smd custom
			(at 0 0.8001 270)
			(size 0.10414 0.10414)
			(layers "B.Cu" "B.Mask" "B.Paste")
			(net "GND")
			(options
				(clearance outline)
				(anchor circle)
			)
			(primitives
				(gr_poly
					(pts
						(xy -0.20828 -0.08636) (xy -0.20828 0.08636) (xy -0.08636 0.20828) (xy 0.086614 0.20828) (xy 0.20828 0.086614)
						(xy 0.20828 -0.08636) (xy 0.08636 -0.20828) (xy -0.08636 -0.20828)
					)
					(width 0)
					(fill yes)
				)
			)
		)
		(zone
			(layer "B.Cu")
			(hatch none 0.5)
			(connect_pads
				(clearance 0)
			)
			(min_thickness 0.25)
			(keepout
				(tracks not_allowed)
				(vias allowed)
				(pads allowed)
				(copperpour not_allowed)
				(footprints allowed)
			)
			(placement
				(enabled no)
				(sheetname "")
			)
			(fill
				(thermal_gap 0.5)
				(thermal_bridge_width 0.5)
				(island_removal_mode 0)
			)
			(polygon
				(pts
					(xy 393.7381 -106.37266) (xy 393.7381 -105.99166) (xy 393.56284 -105.99166) (xy 393.562586 -106.37266)
				)
			)
		)
		(zone
			(layer "B.Cu")
			(hatch none 0.5)
			(connect_pads
				(clearance 0)
			)
			(min_thickness 0.25)
			(keepout
				(tracks allowed)
				(vias not_allowed)
				(pads allowed)
				(copperpour not_allowed)
				(footprints allowed)
			)
			(placement
				(enabled no)
				(sheetname "")
			)
			(fill
				(thermal_gap 0.5)
				(thermal_bridge_width 0.5)
				(island_removal_mode 0)
			)
			(polygon
				(pts
					(xy 393.7381 -106.37266) (xy 393.7381 -105.99166) (xy 393.56284 -105.99166) (xy 393.562586 -106.37266)
				)
			)
		)
	)
	(footprint ""
		(layer "B.Cu")
		(at 493.137698 -46.533816 -90)
		(property "Reference" "Q25W4"
			(at 0 -0.81788 270)
			(unlocked yes)
			(layer "B.SilkS")
			(effects
				(font
					(size 0.4064 0.254)
					(thickness 0.1524)
				)
				(justify left mirror)
			)
		)
		(property "Value" ""
			(at 0 0 90)
			(layer "B.Fab")
			(effects
				(font
					(size 1.27 1.27)
				)
				(justify mirror)
			)
		)
		(duplicate_pad_numbers_are_jumpers no)
		(fp_circle
			(center 0.848614 -0.6477)
			(end 0.848614 -0.7747)
			(stroke
				(width 0.254)
				(type default)
			)
			(fill no)
			(layer "B.SilkS")
		)
		(fp_poly
			(pts
				(xy -0.21463 -0.450088) (xy -1.56337 -0.450088) (xy -1.56337 1.75006) (xy -0.21463 1.75006)
			)
			(stroke
				(width 0)
				(type default)
			)
			(fill no)
			(layer "B.CrtYd")
		)
		(fp_line
			(start -1.56337 1.75006)
			(end -0.21463 1.75006)
			(stroke
				(width 0.1)
				(type default)
			)
			(layer "B.Fab")
		)
		(fp_line
			(start -0.21463 1.75006)
			(end -0.21463 -0.450088)
			(stroke
				(width 0.1)
				(type default)
			)
			(layer "B.Fab")
		)
		(fp_line
			(start -1.56337 -0.450088)
			(end -1.56337 1.75006)
			(stroke
				(width 0.1)
				(type default)
			)
			(layer "B.Fab")
		)
		(fp_line
			(start -0.21463 -0.450088)
			(end -1.56337 -0.450088)
			(stroke
				(width 0.1)
				(type default)
			)
			(layer "B.Fab")
		)
		(fp_circle
			(center 0.848614 -0.6477)
			(end 0.848614 -0.7747)
			(stroke
				(width 0.254)
				(type default)
			)
			(fill no)
			(layer "B.Fab")
		)
		(pad "1" smd rect
			(at 0 0 90)
			(size 1.016 0.381)
			(layers "B.Cu" "B.Mask" "B.Paste")
			(net "I2C_BMC_VGA_DDC_SCL")
		)
		(pad "2" smd rect
			(at 0 0.649986 90)
			(size 1.016 0.381)
			(layers "B.Cu" "B.Mask" "B.Paste")
			(net "Q25W1_GATE")
		)
		(pad "3" smd rect
			(at 0 1.299972 90)
			(size 1.016 0.381)
			(layers "B.Cu" "B.Mask" "B.Paste")
			(net "I2C_BMC_VGA_DDC_SDA_G")
		)
		(pad "4" smd rect
			(at -1.778 1.299972 90)
			(size 1.016 0.381)
			(layers "B.Cu" "B.Mask" "B.Paste")
			(net "I2C_BMC_VGA_DDC_SDA")
		)
		(pad "5" smd rect
			(at -1.778 0.649986 90)
			(size 1.016 0.381)
			(layers "B.Cu" "B.Mask" "B.Paste")
			(net "Q25W2_GATE")
		)
		(pad "6" smd rect
			(at -1.778 0 90)
			(size 1.016 0.381)
			(layers "B.Cu" "B.Mask" "B.Paste")
			(net "I2C_BMC_VGA_DDC_SCL_G")
		)
	)
	(footprint ""
		(layer "B.Cu")
		(at 423.342054 -44.706794 180)
		(property "Reference" "R25W184"
			(at 0.8382 -0.67818 180)
			(unlocked yes)
			(layer "B.SilkS")
			(effects
				(font
					(size 0.4064 0.254)
					(thickness 0.1524)
				)
				(justify left mirror)
			)
		)
		(property "Value" ""
			(at 0 0 0)
			(layer "B.Fab")
			(effects
				(font
					(size 1.27 1.27)
				)
				(justify mirror)
			)
		)
		(duplicate_pad_numbers_are_jumpers no)
		(fp_poly
			(pts
				(xy 0.2794 -0.1016) (xy -0.2794 -0.1016) (xy -0.2794 0.9906) (xy 0.2794 0.9906)
			)
			(stroke
				(width 0)
				(type default)
			)
			(fill no)
			(layer "B.CrtYd")
		)
		(fp_line
			(start 0.2794 0.9906)
			(end -0.2794 0.9906)
			(stroke
				(width 0.1)
				(type default)
			)
			(layer "B.Fab")
		)
		(fp_line
			(start 0.2794 -0.1016)
			(end 0.2794 0.9906)
			(stroke
				(width 0.1)
				(type default)
			)
			(layer "B.Fab")
		)
		(fp_line
			(start -0.2794 0.9906)
			(end -0.2794 -0.1016)
			(stroke
				(width 0.1)
				(type default)
			)
			(layer "B.Fab")
		)
		(fp_line
			(start -0.2794 -0.1016)
			(end 0.2794 -0.1016)
			(stroke
				(width 0.1)
				(type default)
			)
			(layer "B.Fab")
		)
		(pad "1" smd rect
			(at 0 0)
			(size 0.508 0.508)
			(layers "B.Cu" "B.Mask" "B.Paste")
			(net "RST_BMC_PLTRST_BUF_N")
		)
		(pad "2" smd rect
			(at 0 0.889)
			(size 0.508 0.508)
			(layers "B.Cu" "B.Mask" "B.Paste")
			(net "RST_PLTRST_BUF_N")
		)
		(zone
			(layer "B.Cu")
			(hatch none 0.5)
			(connect_pads
				(clearance 0)
			)
			(min_thickness 0.25)
			(keepout
				(tracks not_allowed)
				(vias allowed)
				(pads allowed)
				(copperpour not_allowed)
				(footprints allowed)
			)
			(placement
				(enabled no)
				(sheetname "")
			)
			(fill
				(thermal_gap 0.5)
				(thermal_bridge_width 0.5)
				(island_removal_mode 0)
			)
			(polygon
				(pts
					(xy 423.088054 -45.341794) (xy 423.596054 -45.341794) (xy 423.596054 -44.960794) (xy 423.088054 -44.960794)
				)
			)
		)
		(zone
			(layer "B.Cu")
			(hatch none 0.5)
			(connect_pads
				(clearance 0)
			)
			(min_thickness 0.25)
			(keepout
				(tracks allowed)
				(vias not_allowed)
				(pads allowed)
				(copperpour not_allowed)
				(footprints allowed)
			)
			(placement
				(enabled no)
				(sheetname "")
			)
			(fill
				(thermal_gap 0.5)
				(thermal_bridge_width 0.5)
				(island_removal_mode 0)
			)
			(polygon
				(pts
					(xy 423.088054 -44.960794) (xy 423.596054 -44.960794) (xy 423.596054 -45.341794) (xy 423.088054 -45.341794)
				)
			)
		)
	)
	(footprint ""
		(layer "B.Cu")
		(at 321.1957 -28.36418 90)
		(property "Reference" "R4T8"
			(at 0 0 90)
			(layer "B.SilkS")
			(hide yes)
			(effects
				(font
					(size 1.27 1.27)
				)
				(justify mirror)
			)
		)
		(property "Value" ""
			(at 0 0 90)
			(layer "B.Fab")
			(effects
				(font
					(size 1.27 1.27)
				)
				(justify mirror)
			)
		)
		(duplicate_pad_numbers_are_jumpers no)
		(fp_poly
			(pts
				(xy 0.2794 -0.1016) (xy -0.2794 -0.1016) (xy -0.2794 0.9906) (xy 0.2794 0.9906)
			)
			(stroke
				(width 0)
				(type default)
			)
			(fill no)
			(layer "B.CrtYd")
		)
		(fp_line
			(start 0.2794 -0.1016)
			(end 0.2794 0.9906)
			(stroke
				(width 0.1)
				(type default)
			)
			(layer "B.Fab")
		)
		(fp_line
			(start -0.2794 -0.1016)
			(end 0.2794 -0.1016)
			(stroke
				(width 0.1)
				(type default)
			)
			(layer "B.Fab")
		)
		(fp_line
			(start 0.2794 0.9906)
			(end -0.2794 0.9906)
			(stroke
				(width 0.1)
				(type default)
			)
			(layer "B.Fab")
		)
		(fp_line
			(start -0.2794 0.9906)
			(end -0.2794 -0.1016)
			(stroke
				(width 0.1)
				(type default)
			)
			(layer "B.Fab")
		)
		(pad "1" smd rect
			(at 0 0 270)
			(size 0.508 0.508)
			(layers "B.Cu" "B.Mask" "B.Paste")
			(net "PVPP_ABC")
		)
		(pad "2" smd rect
			(at 0 0.889 270)
			(size 0.508 0.508)
			(layers "B.Cu" "B.Mask" "B.Paste")
			(net "SMB_DDR_ABC_VPP_SDA_R")
		)
		(zone
			(layer "B.Cu")
			(hatch none 0.5)
			(connect_pads
				(clearance 0)
			)
			(min_thickness 0.25)
			(keepout
				(tracks allowed)
				(vias not_allowed)
				(pads allowed)
				(copperpour not_allowed)
				(footprints allowed)
			)
			(placement
				(enabled no)
				(sheetname "")
			)
			(fill
				(thermal_gap 0.5)
				(thermal_bridge_width 0.5)
				(island_removal_mode 0)
			)
			(polygon
				(pts
					(xy 321.4497 -28.61818) (xy 321.4497 -28.11018) (xy 321.8307 -28.11018) (xy 321.8307 -28.61818)
				)
			)
		)
		(zone
			(layer "B.Cu")
			(hatch none 0.5)
			(connect_pads
				(clearance 0)
			)
			(min_thickness 0.25)
			(keepout
				(tracks not_allowed)
				(vias allowed)
				(pads allowed)
				(copperpour not_allowed)
				(footprints allowed)
			)
			(placement
				(enabled no)
				(sheetname "")
			)
			(fill
				(thermal_gap 0.5)
				(thermal_bridge_width 0.5)
				(island_removal_mode 0)
			)
			(polygon
				(pts
					(xy 321.8307 -28.61818) (xy 321.8307 -28.11018) (xy 321.4497 -28.11018) (xy 321.4497 -28.61818)
				)
			)
		)
	)
	(footprint ""
		(layer "B.Cu")
		(at 370.078 -28.448)
		(property "Reference" "RN8F2"
			(at 0.8382 -0.67818 0)
			(unlocked yes)
			(layer "B.SilkS")
			(effects
				(font
					(size 0.4064 0.254)
					(thickness 0.1524)
				)
				(justify left mirror)
			)
		)
		(property "Value" ""
			(at 0 0 0)
			(layer "B.Fab")
			(effects
				(font
					(size 1.27 1.27)
				)
				(justify mirror)
			)
		)
		(duplicate_pad_numbers_are_jumpers no)
		(fp_poly
			(pts
				(xy 0.2794 -0.1016) (xy -0.2794 -0.1016) (xy -0.2794 0.9906) (xy 0.2794 0.9906)
			)
			(stroke
				(width 0)
				(type default)
			)
			(fill no)
			(layer "B.CrtYd")
		)
		(fp_line
			(start -0.2794 -0.1016)
			(end 0.2794 -0.1016)
			(stroke
				(width 0.1)
				(type default)
			)
			(layer "B.Fab")
		)
		(fp_line
			(start -0.2794 0.9906)
			(end -0.2794 -0.1016)
			(stroke
				(width 0.1)
				(type default)
			)
			(layer "B.Fab")
		)
		(fp_line
			(start 0.2794 -0.1016)
			(end 0.2794 0.9906)
			(stroke
				(width 0.1)
				(type default)
			)
			(layer "B.Fab")
		)
		(fp_line
			(start 0.2794 0.9906)
			(end -0.2794 0.9906)
			(stroke
				(width 0.1)
				(type default)
			)
			(layer "B.Fab")
		)
		(pad "1" smd rect
			(at 0 0 180)
			(size 0.508 0.508)
			(layers "B.Cu" "B.Mask" "B.Paste")
			(net "P3V3_STBY")
		)
		(pad "2" smd rect
			(at 0 0.889 180)
			(size 0.508 0.508)
			(layers "B.Cu" "B.Mask" "B.Paste")
			(net "TPM_SPI_BMC_WP_N")
		)
		(zone
			(layer "B.Cu")
			(hatch none 0.5)
			(connect_pads
				(clearance 0)
			)
			(min_thickness 0.25)
			(keepout
				(tracks allowed)
				(vias not_allowed)
				(pads allowed)
				(copperpour not_allowed)
				(footprints allowed)
			)
			(placement
				(enabled no)
				(sheetname "")
			)
			(fill
				(thermal_gap 0.5)
				(thermal_bridge_width 0.5)
				(island_removal_mode 0)
			)
			(polygon
				(pts
					(xy 370.332 -28.194) (xy 369.824 -28.194) (xy 369.824 -27.813) (xy 370.332 -27.813)
				)
			)
		)
		(zone
			(layer "B.Cu")
			(hatch none 0.5)
			(connect_pads
				(clearance 0)
			)
			(min_thickness 0.25)
			(keepout
				(tracks not_allowed)
				(vias allowed)
				(pads allowed)
				(copperpour not_allowed)
				(footprints allowed)
			)
			(placement
				(enabled no)
				(sheetname "")
			)
			(fill
				(thermal_gap 0.5)
				(thermal_bridge_width 0.5)
				(island_removal_mode 0)
			)
			(polygon
				(pts
					(xy 370.332 -27.813) (xy 369.824 -27.813) (xy 369.824 -28.194) (xy 370.332 -28.194)
				)
			)
		)
	)
	(footprint ""
		(layer "B.Cu")
		(at 476.1992 -48.5394 -90)
		(property "Reference" "C9F2"
			(at 0 0 90)
			(layer "B.SilkS")
			(hide yes)
			(effects
				(font
					(size 1.27 1.27)
				)
				(justify mirror)
			)
		)
		(property "Value" "*"
			(at 0.0762 -6.2357 270)
			(unlocked yes)
			(layer "B.Fab")
			(hide yes)
			(effects
				(font
					(size 1.27 1.016)
					(thickness 0.1524)
				)
				(justify mirror)
			)
		)
		(property "Device Type" "SC22U16V5MX-4-GP_SMD-BCG5-SC22A"
			(at 0.0762 -8.2677 270)
			(unlocked yes)
			(layer "B.Fab")
			(hide yes)
			(effects
				(font
					(size 1.27 1.016)
					(thickness 0.1524)
				)
				(justify mirror)
			)
		)
		(duplicate_pad_numbers_are_jumpers no)
		(fp_line
			(start -0.635 0)
			(end 0.635 0)
			(stroke
				(width 0.508)
				(type default)
			)
			(layer "B.SilkS")
		)
		(fp_rect
			(start 0.9652 1.778)
			(end -0.9652 -1.778)
			(stroke
				(width 0)
				(type default)
			)
			(fill no)
			(layer "B.CrtYd")
		)
		(fp_poly
			(pts
				(xy 0.9652 -1.778) (xy -0.9652 -1.778) (xy -0.9652 1.778) (xy 0.9652 1.778)
			)
			(stroke
				(width 0)
				(type default)
			)
			(fill no)
			(layer "B.Fab")
		)
		(pad "1" smd rect
			(at 0 -0.9652 90)
			(size 1.397 1.143)
			(layers "B.Cu" "B.Mask" "B.Paste")
			(net "P3V3_STBY")
		)
		(pad "2" smd rect
			(at 0 0.9652 90)
			(size 1.397 1.143)
			(layers "B.Cu" "B.Mask" "B.Paste")
			(net "GND")
		)
	)
	(footprint ""
		(layer "B.Cu")
		(at 361.444794 -44.845986 -90)
		(property "Reference" "R2T38"
			(at 0 0 90)
			(layer "B.SilkS")
			(hide yes)
			(effects
				(font
					(size 1.27 1.27)
				)
				(justify mirror)
			)
		)
		(property "Value" ""
			(at 0 0 90)
			(layer "B.Fab")
			(effects
				(font
					(size 1.27 1.27)
				)
				(justify mirror)
			)
		)
		(duplicate_pad_numbers_are_jumpers no)
		(fp_poly
			(pts
				(xy 0.2794 -0.1016) (xy -0.2794 -0.1016) (xy -0.2794 0.9906) (xy 0.2794 0.9906)
			)
			(stroke
				(width 0)
				(type default)
			)
			(fill no)
			(layer "B.CrtYd")
		)
		(fp_line
			(start -0.2794 0.9906)
			(end -0.2794 -0.1016)
			(stroke
				(width 0.1)
				(type default)
			)
			(layer "B.Fab")
		)
		(fp_line
			(start 0.2794 0.9906)
			(end -0.2794 0.9906)
			(stroke
				(width 0.1)
				(type default)
			)
			(layer "B.Fab")
		)
		(fp_line
			(start -0.2794 -0.1016)
			(end 0.2794 -0.1016)
			(stroke
				(width 0.1)
				(type default)
			)
			(layer "B.Fab")
		)
		(fp_line
			(start 0.2794 -0.1016)
			(end 0.2794 0.9906)
			(stroke
				(width 0.1)
				(type default)
			)
			(layer "B.Fab")
		)
		(pad "1" smd rect
			(at 0 0 90)
			(size 0.508 0.508)
			(layers "B.Cu" "B.Mask" "B.Paste")
			(net "FM_CPU0_PROCHOT_LVT3_K_N")
		)
		(pad "2" smd rect
			(at 0 0.889 90)
			(size 0.508 0.508)
			(layers "B.Cu" "B.Mask" "B.Paste")
			(net "FM_CPU0_PROCHOT_LVT3_N")
		)
		(zone
			(layer "B.Cu")
			(hatch none 0.5)
			(connect_pads
				(clearance 0)
			)
			(min_thickness 0.25)
			(keepout
				(tracks not_allowed)
				(vias allowed)
				(pads allowed)
				(copperpour not_allowed)
				(footprints allowed)
			)
			(placement
				(enabled no)
				(sheetname "")
			)
			(fill
				(thermal_gap 0.5)
				(thermal_bridge_width 0.5)
				(island_removal_mode 0)
			)
			(polygon
				(pts
					(xy 360.809794 -44.591986) (xy 360.809794 -45.099986) (xy 361.190794 -45.099986) (xy 361.190794 -44.591986)
				)
			)
		)
		(zone
			(layer "B.Cu")
			(hatch none 0.5)
			(connect_pads
				(clearance 0)
			)
			(min_thickness 0.25)
			(keepout
				(tracks allowed)
				(vias not_allowed)
				(pads allowed)
				(copperpour not_allowed)
				(footprints allowed)
			)
			(placement
				(enabled no)
				(sheetname "")
			)
			(fill
				(thermal_gap 0.5)
				(thermal_bridge_width 0.5)
				(island_removal_mode 0)
			)
			(polygon
				(pts
					(xy 361.190794 -44.591986) (xy 361.190794 -45.099986) (xy 360.809794 -45.099986) (xy 360.809794 -44.591986)
				)
			)
		)
	)
)
